﻿Index,Quantity,Part Number,Manufacturer Part Number,Description,Customer Reference,Available,Backorder,Unit Price,Extended Price USD
1,4,399-1091-1-ND,C0603C103K5RACTU,CAP CER 10000PF 50V X7R 0603,"TIME CARD - C3, C4, C67, C76",4,0,0.1,0.40
2,1,609-5379-1-ND,10118192-0002LF,CONN RCPT USB2.0 MICRO B SMD R/A,TIME CARD - J2,1,0,0.42,0.42
3,1,P4.70KHCT-ND,ERJ-3EKF4701V,RES SMD 4.7K OHM 1% 1/10W 0603,TIME CARD - R22,1,0,0.1,0.10
4,1,P26.1KHCT-ND,ERJ-3EKF2612V,RES SMD 26.1K OHM 1% 1/10W 0603,TIME CARD - R5,1,0,0.1,0.10
5,4,A118077CT-ND,1909763-1,CONN UMCC JACK STR 50OHM SMD,"TIME CARD - AN5, AN6, AN7, AN8",4,0,0.46,1.84
6,11,P0.0JCT-ND,ERJ-2GE0R00X,RES SMD 0 OHM JUMPER 1/10W 0402,"TIME CARD - R[10-16, R32, R17, R23, R24",11,0,0.019,0.21
7,4,255-3246-1-ND,AXK680347YG,CONN HDR 80POS SMD GOLD,"TIME CARD - P1A, P1B, P1C, P1D",4,0,2.88,11.52
8,4,ARFX1232-ND,901-143-6RFX,CONN SMA JACK R/A 50 OHM PCB,"TIME CARD - AN1, AN2, AN3, AN4",4,0,7.94,31.76
9,2,399-5089-1-ND,C0603C104K5RACTU,CAP CER 0.1UF 50V X7R 0603,"TIME CARD - C19, C21",2,0,0.12,0.24
10,15,490-12323-6-ND,GRT188R61E106ME13D,CAP CER 10UF 25V X5R 0603,"TIME CARD-C[5-8,1,13,14,55,56,58,60,62,87,89,92]",15,0,0.81667,12.25
11,2,587-2985-1-ND,TMK212BBJ106KG-T,CAP CER 10UF 25V X5R 0805,"TIME CARD - C55, C92",2,0,0.2,0.40
12,2,445-12207-1-ND,CGA2B3X5R1H333K050BB,CAP CER 0.033UF 50V X5R 0402,"TIME CARD - C20, C22",2,0,0.1,0.20
13,4,490-9952-1-ND,GRM219R61C226ME15L,CAP CER 22UF 16V X5R 0805,"TIME CARD - C72, C73, C74, C75",4,0,0.52,2.08
14,2,399-1053-1-ND,C0603C220J5GACTU,CAP CER 22PF 50V C0G/NP0 0603,"TIME CARD - C85, C86",2,0,0.15,0.30
15,4,SMCJ6.5CALFCT-ND,SMCJ6.5CA,TVS DIODE 6.5V 11.2V DO214AB,"TIME CARD - D15, D16, D17, D18",4,0,0.61,2.44
16,1,CP-002A-ND,PJ-002A,CONN PWR JACK 2X5.5MM SOLDER,TIME CARD - J1,1,0,0.6,0.60
17,2,445-1565-1-ND,MPZ1608S221ATA00,FERRITE BEAD 220 OHM 0603 1LN,"TIME CARD - FB2, FB3",2,0,0.1,0.20
18,4,BAT54SWQ-7-FDICT-ND,BAT54SWQ-7-F,DIODE ARRAY SCHOTTKY 30V SOT323,"TIME CARD - D5, D6, D7, D8",4,0,0.32,1.28
19,1,SF-0603S200-2CT-ND,SF-0603S200-2,FUSE BOARD MOUNT 2A 32VDC 0603,TIME CARD - F1,1,0,0.8,0.80
20,1,A31727CT-ND,1734035-2,CONN RCPT USB2.0 MINI B SMD R/A,TIME CARD - J3,1,0,1.66,1.66
21,4,541-33.0CCT-ND,CRCW080533R0FKEA,RES SMD 33 OHM 1% 1/8W 0805,"TIME CARD - R18, R19, R20, R21",4,0,0.1,0.40
22,2,P2.20KHCT-ND,ERJ-3EKF2201V,RES SMD 2.2K OHM 1% 1/10W 0603,"TIME CARD - R8, R9",2,0,0.1,0.20
23,1,CKC5106-ND,L101011MS02Q,SWITCH SLIDE SPST 4A 125V,TIME CARD - SW1,1,0,1.83,1.83
24,2,SW1020CT-ND,B3U-1000P,SWITCH TACTILE SPST-NO 0.05A 12V,"TIME CARD - S5, S6",2,0,0.92,1.84
25,1,1888-1000-1-ND,BNO080,IMU ACCEL/GYRO/MAG I2C 32BIT,TIME CARD - U8,1,0,12.26,12.26
26,1,WM24007CT-ND,0529910208,CONN RCPT 20POS SMD GOLD,TIME CARD - U10B,1,0,1.28,1.28
27,2,768-1135-1-ND,FT230XS-R,IC USB SERIAL BASIC UART 16SSOP,"TIME CARD - U6, U16",2,0,2.04,4.08
28,2,P1.00KHCT-ND,ERJ-3EKF1001V,RES SMD 1K OHM 1% 1/10W 0603,"TIME CARD - R34, R35",2,0,0.1,0.20
29,2,1589-1524-1-ND,MP1482DS-LF-Z,IC REG BUCK ADJUSTABLE 2A 8SOIC,"TIME CARD - U1, U2",2,0,2.92,5.84
30,1,SAM14025CT-ND,HTST-105-01-L-DV-A-P-TR,CONN HEADER SMD 10POS 2.54MM,TIME CARD - U5,1,0,3.45,3.45
31,2,672-RCB-F9T-ND,RCB-F9T,ZED-F9T TIMING BOARD,"TIME CARD - GPS1, GPS2",2,0,278.44,556.88
32,2,SAM11876-ND,SQW-104-01-F-D-VS,CONN RCPT 8POS 0.079 GOLD SMD,"TIME CARD - U9, U14",2,0,1.62,3.24
33,2,SRR1240-100MCT-ND,SRR1240-100M,FIXED IND 10UH 4A 32 MOHM SMD,"TIME CARD - L1, L2",2,0,1.09,2.18
34,2,WM10869-ND,0455580003,CONN HEADER R/A 6POS 4.2MM,TIME CARD - J2,2,0,0.85,1.70
35,4,399-15436-1-ND,C0805C105K5PAC7800,CAP CER 1UF 50V X5R 0805,"TIME CARD - C54, C91, C65, C84",4,0,0.35,1.40
36,1,535-10241-1-ND,ABS25-32.768KHZ-6-1-T,CRYSTAL 32.7680KHZ 6PF SMD,TIME CARD - X1,1,0,0.67,0.67
37,3,NRVTS245ESFT1GOSCT-ND,NRVTS245ESFT1G,DIODE SCHOTTKY 45V 2A SOD123FL,"TIME CARD - D1, D2, D3",3,0,0.33,0.99
38,1,732-12325-1-ND,79527141,BATTERY HOLDER COIN 20MM SMD,TIME CARD - BT1,1,0,1.86,1.86
39,1,828-1079-1-ND,BMP388,SENSOR PRESSURE ABS,TIME CARD - IC?,1,0,3.47,3.47
40,2,SAM1038-03-ND,TSW-103-08-G-S,CONN HEADER VERT 3POS 2.54MM,"TIME CARD - JP1, JP2",2,0,0.39,0.78
41,1,DS3231SN#T&RCT-ND,DS3231SN#T&R,IC RTC CLK/CALENDAR I2C 16-SOIC,TIME CARD - U5,1,0,8.82,8.82
42,31,445-6899-1-ND,CGA2B3X7R1H104K050BB,CAP CER 0.1UF 50V X7R 0402,"C[2,9,10-12,15-18,44-53,77-83,57,59,61,63,88,90]",31,0,0.107,3.32
43,7,67-1548-1-ND,SML-LX0603IW-TR,LED RED DIFFUSED SMD,"TIME CARD - D4, D9, D10, D11, D12, D13, D14",7,0,0.36,2.52
44,5,P200HCT-ND,ERJ-3EKF2000V,RES SMD 200 OHM 1% 1/10W 0603,"TIME CARD - R1, R28, R29, R30, R31",5,0,0.1,0.50
45,7,P10.0KHCT-ND,ERJ-3EKF1002V,RES SMD 10K OHM 1% 1/10W 0603,"TIME CARD - R6, R7, R27, R32, R33, R42, R43",7,0,0.1,0.70
46,2,P499LCT-ND,ERJ-2RKF4990X,RES SMD 499 OHM 1% 1/10W 0402,"TIME CARD - R25, R26",2,0,0.1,0.20
47,3,P47.0KHCT-ND,ERJ-3EKF4702V,RES SMD 47K OHM 1% 1/10W 0603,"TIME CARD -  R2, R3, R4",3,0,0.1,0.30